# S9S_MB_2U (Grand Teton) — schematic netlist excerpt (pin names and nets, part order shuffled) for the footprints in the layout excerpt that follows; sources: Cadence DE-HDL packaged netlist, KiCad conversion of 03242023_DA0F0TMBIJ0_F0T_Motherboard_J_brd_V01_OCP.brd

R2906  Q_RES  0 5% CHIP  pkg 0402LF  page 245 : A = FM_GPU_HSC_EN_BUF_R1 ; B = FM_GPU_HSC_EN_BUF
R4556  Q_RES  33.2 1% CHIP  pkg 0402LF  page 215 : A = HGX_DETECT_N_R ; B = HGX_DETECT_N

(kicad_pcb
	(version 20260206)
	(generator "pcbnew")
	(generator_version "10.0")
	(general
		(thickness 1.6)
		(legacy_teardrops no)
	)
	(paper "A4")
	(title_block
		(title "03242023_DA0F0TMBIJ0_F0T_Motherboard_J_brd_V01_OCP.brd")
		(comment 1 "Grand Teton / footprints 5193-5194 of 6105")
	)
	(layers
		(0 "F.Cu" signal "TOP")
		(4 "In1.Cu" signal "GND")
		(6 "In2.Cu" signal "IN1")
		(8 "In3.Cu" signal "GND1")
		(10 "In4.Cu" signal "IN2")
		(12 "In5.Cu" signal "GND2")
		(14 "In6.Cu" signal "IN3")
		(16 "In7.Cu" signal "GND3")
		(18 "In8.Cu" signal "VCC")
		(20 "In9.Cu" signal "VCC1")
		(22 "In10.Cu" signal "GND4")
		(24 "In11.Cu" signal "IN4")
		(26 "In12.Cu" signal "GND5")
		(28 "In13.Cu" signal "IN5")
		(30 "In14.Cu" signal "GND6")
		(32 "In15.Cu" signal "IN6")
		(34 "In16.Cu" signal "GND7")
		(2 "B.Cu" signal "BOTTOM")
		(9 "F.Adhes" user "F.Adhesive")
		(11 "B.Adhes" user "B.Adhesive")
		(13 "F.Paste" user "Package Geometry/Pastemask Top")
		(15 "B.Paste" user "Package Geometry/Pastemask Bottom")
		(5 "F.SilkS" user "Ref Des/Silkscreen Top")
		(7 "B.SilkS" user "Ref Des/Silkscreen Bottom")
		(1 "F.Mask" user "Board Geometry/Soldermask Top")
		(3 "B.Mask" user "Board Geometry/Soldermask Bottom")
		(17 "Dwgs.User" user "User.Drawings")
		(19 "Cmts.User" user "User.Comments")
		(21 "Eco1.User" user "User.Eco1")
		(23 "Eco2.User" user "User.Eco2")
		(25 "Edge.Cuts" user "Board Geometry/Outline")
		(27 "Margin" user)
		(31 "F.CrtYd" user "Package Geometry/Place Bound Top")
		(29 "B.CrtYd" user "Package Geometry/Place Bound Bottom")
		(35 "F.Fab" user "Ref Des/Assembly Top")
		(33 "B.Fab" user "Ref Des/Assembly Bottom")
	)
	(footprint ""
		(layer "B.Cu")
		(at 99.53752 -422.145968 90)
		(property "Reference" "R4556"
			(at 0 0 90)
			(layer "B.SilkS")
			(hide yes)
			(effects
				(font
					(size 1.27 1.27)
				)
				(justify mirror)
			)
		)
		(property "Value" ""
			(at 0 0 90)
			(layer "B.Fab")
			(effects
				(font
					(size 1.27 1.27)
				)
				(justify mirror)
			)
		)
		(duplicate_pad_numbers_are_jumpers no)
		(fp_line
			(start 0.7874 -0.4064)
			(end -0.7874 -0.4064)
			(stroke
				(width 0.1524)
				(type default)
			)
			(layer "B.SilkS")
		)
		(fp_line
			(start -0.7874 -0.4064)
			(end -0.7874 0.4064)
			(stroke
				(width 0.1524)
				(type default)
			)
			(layer "B.SilkS")
		)
		(fp_line
			(start 0.7874 0.4064)
			(end 0.7874 -0.4064)
			(stroke
				(width 0.1524)
				(type default)
			)
			(layer "B.SilkS")
		)
		(fp_line
			(start -0.7874 0.4064)
			(end 0.7874 0.4064)
			(stroke
				(width 0.1524)
				(type default)
			)
			(layer "B.SilkS")
		)
		(fp_line
			(start 0.67945 -0.305054)
			(end 0.12065 -0.305054)
			(stroke
				(width 0.1)
				(type default)
			)
			(layer "B.Fab")
		)
		(fp_line
			(start 0.12065 -0.305054)
			(end 0.12065 -0.2794)
			(stroke
				(width 0.1)
				(type default)
			)
			(layer "B.Fab")
		)
		(fp_line
			(start -0.12065 -0.3048)
			(end -0.67945 -0.3048)
			(stroke
				(width 0.1)
				(type default)
			)
			(layer "B.Fab")
		)
		(fp_line
			(start -0.67945 -0.3048)
			(end -0.67945 0.3048)
			(stroke
				(width 0.1)
				(type default)
			)
			(layer "B.Fab")
		)
		(fp_line
			(start 0.12065 -0.2794)
			(end -0.12065 -0.2794)
			(stroke
				(width 0.1)
				(type default)
			)
			(layer "B.Fab")
		)
		(fp_line
			(start -0.12065 -0.2794)
			(end -0.12065 -0.3048)
			(stroke
				(width 0.1)
				(type default)
			)
			(layer "B.Fab")
		)
		(fp_line
			(start 0.12065 0.2794)
			(end 0.12065 0.3048)
			(stroke
				(width 0.1)
				(type default)
			)
			(layer "B.Fab")
		)
		(fp_line
			(start -0.120396 0.2794)
			(end 0.12065 0.2794)
			(stroke
				(width 0.1)
				(type default)
			)
			(layer "B.Fab")
		)
		(fp_line
			(start 0.67945 0.3048)
			(end 0.67945 -0.305054)
			(stroke
				(width 0.1)
				(type default)
			)
			(layer "B.Fab")
		)
		(fp_line
			(start 0.12065 0.3048)
			(end 0.67945 0.3048)
			(stroke
				(width 0.1)
				(type default)
			)
			(layer "B.Fab")
		)
		(fp_line
			(start -0.120396 0.3048)
			(end -0.120396 0.2794)
			(stroke
				(width 0.1)
				(type default)
			)
			(layer "B.Fab")
		)
		(fp_line
			(start -0.67945 0.3048)
			(end -0.120396 0.3048)
			(stroke
				(width 0.1)
				(type default)
			)
			(layer "B.Fab")
		)
		(pad "1" smd circle
			(at 0.40005 0 270)
			(size 0 0)
			(layers "B.Cu" "B.Mask" "B.Paste")
			(net "HGX_DETECT_N_R")
		)
		(pad "2" smd circle
			(at -0.40005 0 270)
			(size 0 0)
			(layers "B.Cu" "B.Mask" "B.Paste")
			(net "HGX_DETECT_N")
		)
	)
	(footprint ""
		(layer "B.Cu")
		(at 237.230666 -422.993058 90)
		(property "Reference" "R2906"
			(at 0 0 90)
			(layer "B.SilkS")
			(hide yes)
			(effects
				(font
					(size 1.27 1.27)
				)
				(justify mirror)
			)
		)
		(property "Value" ""
			(at 0 0 90)
			(layer "B.Fab")
			(effects
				(font
					(size 1.27 1.27)
				)
				(justify mirror)
			)
		)
		(duplicate_pad_numbers_are_jumpers no)
		(fp_line
			(start 0.7874 -0.4064)
			(end -0.7874 -0.4064)
			(stroke
				(width 0.1524)
				(type default)
			)
			(layer "B.SilkS")
		)
		(fp_line
			(start -0.7874 -0.4064)
			(end -0.7874 0.4064)
			(stroke
				(width 0.1524)
				(type default)
			)
			(layer "B.SilkS")
		)
		(fp_line
			(start 0.7874 0.4064)
			(end 0.7874 -0.4064)
			(stroke
				(width 0.1524)
				(type default)
			)
			(layer "B.SilkS")
		)
		(fp_line
			(start -0.7874 0.4064)
			(end 0.7874 0.4064)
			(stroke
				(width 0.1524)
				(type default)
			)
			(layer "B.SilkS")
		)
		(fp_line
			(start 0.67945 -0.305054)
			(end 0.12065 -0.305054)
			(stroke
				(width 0.1)
				(type default)
			)
			(layer "B.Fab")
		)
		(fp_line
			(start 0.12065 -0.305054)
			(end 0.12065 -0.2794)
			(stroke
				(width 0.1)
				(type default)
			)
			(layer "B.Fab")
		)
		(fp_line
			(start -0.12065 -0.3048)
			(end -0.67945 -0.3048)
			(stroke
				(width 0.1)
				(type default)
			)
			(layer "B.Fab")
		)
		(fp_line
			(start -0.67945 -0.3048)
			(end -0.67945 0.3048)
			(stroke
				(width 0.1)
				(type default)
			)
			(layer "B.Fab")
		)
		(fp_line
			(start 0.12065 -0.2794)
			(end -0.12065 -0.2794)
			(stroke
				(width 0.1)
				(type default)
			)
			(layer "B.Fab")
		)
		(fp_line
			(start -0.12065 -0.2794)
			(end -0.12065 -0.3048)
			(stroke
				(width 0.1)
				(type default)
			)
			(layer "B.Fab")
		)
		(fp_line
			(start 0.12065 0.2794)
			(end 0.12065 0.3048)
			(stroke
				(width 0.1)
				(type default)
			)
			(layer "B.Fab")
		)
		(fp_line
			(start -0.120396 0.2794)
			(end 0.12065 0.2794)
			(stroke
				(width 0.1)
				(type default)
			)
			(layer "B.Fab")
		)
		(fp_line
			(start 0.67945 0.3048)
			(end 0.67945 -0.305054)
			(stroke
				(width 0.1)
				(type default)
			)
			(layer "B.Fab")
		)
		(fp_line
			(start 0.12065 0.3048)
			(end 0.67945 0.3048)
			(stroke
				(width 0.1)
				(type default)
			)
			(layer "B.Fab")
		)
		(fp_line
			(start -0.120396 0.3048)
			(end -0.120396 0.2794)
			(stroke
				(width 0.1)
				(type default)
			)
			(layer "B.Fab")
		)
		(fp_line
			(start -0.67945 0.3048)
			(end -0.120396 0.3048)
			(stroke
				(width 0.1)
				(type default)
			)
			(layer "B.Fab")
		)
		(pad "1" smd circle
			(at 0.40005 0 270)
			(size 0 0)
			(layers "B.Cu" "B.Mask" "B.Paste")
			(net "FM_GPU_HSC_EN_BUF_R1")
		)
		(pad "2" smd circle
			(at -0.40005 0 270)
			(size 0 0)
			(layers "B.Cu" "B.Mask" "B.Paste")
			(net "FM_GPU_HSC_EN_BUF")
		)
	)
)
